(kicad_pcb
	(version 20260206)
	(generator "pcbnew")
	(generator_version "10.0")
	(general
		(thickness 1.6)
		(legacy_teardrops no)
	)
	(paper "A4")
	(title_block
		(title "04192023_DAF0TMB3IC0_F0TG_MB_C_brd_V02_OCP.brd")
		(comment 1 "Grand Teton / footprints 8313-8318 of 8354")
	)
	(layers
		(0 "F.Cu" signal "TOP")
		(4 "In1.Cu" signal "GND")
		(6 "In2.Cu" signal "IN1")
		(8 "In3.Cu" signal "GND1")
		(10 "In4.Cu" signal "IN2")
		(12 "In5.Cu" signal "GND2")
		(14 "In6.Cu" signal "IN3")
		(16 "In7.Cu" signal "GND3")
		(18 "In8.Cu" signal "VCC")
		(20 "In9.Cu" signal "VCC1")
		(22 "In10.Cu" signal "GND4")
		(24 "In11.Cu" signal "IN4")
		(26 "In12.Cu" signal "GND5")
		(28 "In13.Cu" signal "IN5")
		(30 "In14.Cu" signal "GND6")
		(32 "In15.Cu" signal "IN6")
		(34 "In16.Cu" signal "GND7")
		(2 "B.Cu" signal "BOTTOM")
		(9 "F.Adhes" user "F.Adhesive")
		(11 "B.Adhes" user "B.Adhesive")
		(13 "F.Paste" user "Package Geometry/Pastemask Top")
		(15 "B.Paste" user "Package Geometry/Pastemask Bottom")
		(5 "F.SilkS" user "Ref Des/Silkscreen Top")
		(7 "B.SilkS" user "Ref Des/Silkscreen Bottom")
		(1 "F.Mask" user "Board Geometry/Soldermask Top")
		(3 "B.Mask" user "Board Geometry/Soldermask Bottom")
		(17 "Dwgs.User" user "User.Drawings")
		(19 "Cmts.User" user "User.Comments")
		(21 "Eco1.User" user "User.Eco1")
		(23 "Eco2.User" user "User.Eco2")
		(25 "Edge.Cuts" user "Board Geometry/Outline")
		(27 "Margin" user)
		(31 "F.CrtYd" user "Package Geometry/Place Bound Top")
		(29 "B.CrtYd" user "Package Geometry/Place Bound Bottom")
		(35 "F.Fab" user "Ref Des/Assembly Top")
		(33 "B.Fab" user "Ref Des/Assembly Bottom")
	)
	(footprint ""
		(layer "B.Cu")
		(at 150.259034 -201.977752 90)
		(property "Reference" "R525"
			(at 0 0 90)
			(layer "B.SilkS")
			(hide yes)
			(effects
				(font
					(size 1.27 1.27)
				)
				(justify mirror)
			)
		)
		(property "Value" ""
			(at 0 0 90)
			(layer "B.Fab")
			(effects
				(font
					(size 1.27 1.27)
				)
				(justify mirror)
			)
		)
		(duplicate_pad_numbers_are_jumpers no)
		(fp_line
			(start 0.7874 -0.4064)
			(end -0.7874 -0.4064)
			(stroke
				(width 0.1524)
				(type default)
			)
			(layer "B.SilkS")
		)
		(fp_line
			(start -0.7874 -0.4064)
			(end -0.7874 0.4064)
			(stroke
				(width 0.1524)
				(type default)
			)
			(layer "B.SilkS")
		)
		(fp_line
			(start 0.7874 0.4064)
			(end 0.7874 -0.4064)
			(stroke
				(width 0.1524)
				(type default)
			)
			(layer "B.SilkS")
		)
		(fp_line
			(start -0.7874 0.4064)
			(end 0.7874 0.4064)
			(stroke
				(width 0.1524)
				(type default)
			)
			(layer "B.SilkS")
		)
		(fp_line
			(start 0.67945 -0.305054)
			(end 0.12065 -0.305054)
			(stroke
				(width 0.1)
				(type default)
			)
			(layer "B.Fab")
		)
		(fp_line
			(start 0.12065 -0.305054)
			(end 0.12065 -0.2794)
			(stroke
				(width 0.1)
				(type default)
			)
			(layer "B.Fab")
		)
		(fp_line
			(start -0.12065 -0.3048)
			(end -0.67945 -0.3048)
			(stroke
				(width 0.1)
				(type default)
			)
			(layer "B.Fab")
		)
		(fp_line
			(start -0.67945 -0.3048)
			(end -0.67945 0.3048)
			(stroke
				(width 0.1)
				(type default)
			)
			(layer "B.Fab")
		)
		(fp_line
			(start 0.12065 -0.2794)
			(end -0.12065 -0.2794)
			(stroke
				(width 0.1)
				(type default)
			)
			(layer "B.Fab")
		)
		(fp_line
			(start -0.12065 -0.2794)
			(end -0.12065 -0.3048)
			(stroke
				(width 0.1)
				(type default)
			)
			(layer "B.Fab")
		)
		(fp_line
			(start 0.12065 0.2794)
			(end 0.12065 0.3048)
			(stroke
				(width 0.1)
				(type default)
			)
			(layer "B.Fab")
		)
		(fp_line
			(start -0.120396 0.2794)
			(end 0.12065 0.2794)
			(stroke
				(width 0.1)
				(type default)
			)
			(layer "B.Fab")
		)
		(fp_line
			(start 0.67945 0.3048)
			(end 0.67945 -0.305054)
			(stroke
				(width 0.1)
				(type default)
			)
			(layer "B.Fab")
		)
		(fp_line
			(start 0.12065 0.3048)
			(end 0.67945 0.3048)
			(stroke
				(width 0.1)
				(type default)
			)
			(layer "B.Fab")
		)
		(fp_line
			(start -0.120396 0.3048)
			(end -0.120396 0.2794)
			(stroke
				(width 0.1)
				(type default)
			)
			(layer "B.Fab")
		)
		(fp_line
			(start -0.67945 0.3048)
			(end -0.120396 0.3048)
			(stroke
				(width 0.1)
				(type default)
			)
			(layer "B.Fab")
		)
		(pad "1" smd circle
			(at 0.40005 0 270)
			(size 0 0)
			(layers "B.Cu" "B.Mask" "B.Paste")
			(net "PVDD18_S5_P1")
		)
		(pad "2" smd circle
			(at -0.40005 0 270)
			(size 0 0)
			(layers "B.Cu" "B.Mask" "B.Paste")
			(net "JTAG_CPU1_TRST_N")
		)
	)
	(footprint ""
		(layer "B.Cu")
		(at 348.888558 -254.06731 180)
		(property "Reference" "C2522"
			(at 0 0 0)
			(layer "B.SilkS")
			(hide yes)
			(effects
				(font
					(size 1.27 1.27)
				)
				(justify mirror)
			)
		)
		(property "Value" ""
			(at 0 0 0)
			(layer "B.Fab")
			(effects
				(font
					(size 1.27 1.27)
				)
				(justify mirror)
			)
		)
		(duplicate_pad_numbers_are_jumpers no)
		(fp_line
			(start 0.7874 0.4064)
			(end 0.7874 -0.4064)
			(stroke
				(width 0.1524)
				(type default)
			)
			(layer "B.SilkS")
		)
		(fp_line
			(start 0.7874 -0.4064)
			(end -0.7874 -0.4064)
			(stroke
				(width 0.1524)
				(type default)
			)
			(layer "B.SilkS")
		)
		(fp_line
			(start -0.7874 0.4064)
			(end 0.7874 0.4064)
			(stroke
				(width 0.1524)
				(type default)
			)
			(layer "B.SilkS")
		)
		(fp_line
			(start -0.7874 -0.4064)
			(end -0.7874 0.4064)
			(stroke
				(width 0.1524)
				(type default)
			)
			(layer "B.SilkS")
		)
		(fp_line
			(start 0.67945 0.3048)
			(end 0.67945 -0.305054)
			(stroke
				(width 0.1)
				(type default)
			)
			(layer "B.Fab")
		)
		(fp_line
			(start 0.67945 -0.305054)
			(end 0.12065 -0.305054)
			(stroke
				(width 0.1)
				(type default)
			)
			(layer "B.Fab")
		)
		(fp_line
			(start 0.12065 0.3048)
			(end 0.67945 0.3048)
			(stroke
				(width 0.1)
				(type default)
			)
			(layer "B.Fab")
		)
		(fp_line
			(start 0.12065 0.2794)
			(end 0.12065 0.3048)
			(stroke
				(width 0.1)
				(type default)
			)
			(layer "B.Fab")
		)
		(fp_line
			(start 0.12065 -0.2794)
			(end -0.12065 -0.2794)
			(stroke
				(width 0.1)
				(type default)
			)
			(layer "B.Fab")
		)
		(fp_line
			(start 0.12065 -0.305054)
			(end 0.12065 -0.2794)
			(stroke
				(width 0.1)
				(type default)
			)
			(layer "B.Fab")
		)
		(fp_line
			(start -0.120396 0.3048)
			(end -0.120396 0.2794)
			(stroke
				(width 0.1)
				(type default)
			)
			(layer "B.Fab")
		)
		(fp_line
			(start -0.120396 0.2794)
			(end 0.12065 0.2794)
			(stroke
				(width 0.1)
				(type default)
			)
			(layer "B.Fab")
		)
		(fp_line
			(start -0.12065 -0.2794)
			(end -0.12065 -0.3048)
			(stroke
				(width 0.1)
				(type default)
			)
			(layer "B.Fab")
		)
		(fp_line
			(start -0.12065 -0.3048)
			(end -0.67945 -0.3048)
			(stroke
				(width 0.1)
				(type default)
			)
			(layer "B.Fab")
		)
		(fp_line
			(start -0.67945 0.3048)
			(end -0.120396 0.3048)
			(stroke
				(width 0.1)
				(type default)
			)
			(layer "B.Fab")
		)
		(fp_line
			(start -0.67945 -0.3048)
			(end -0.67945 0.3048)
			(stroke
				(width 0.1)
				(type default)
			)
			(layer "B.Fab")
		)
		(pad "1" smd circle
			(at 0.40005 0)
			(size 0 0)
			(layers "B.Cu" "B.Mask" "B.Paste")
			(net "PVDD18_S5_P0")
		)
		(pad "2" smd circle
			(at -0.40005 0)
			(size 0 0)
			(layers "B.Cu" "B.Mask" "B.Paste")
			(net "GND")
		)
	)
	(footprint ""
		(layer "B.Cu")
		(at 325.635112 -33.851342 -90)
		(property "Reference" "R3940"
			(at 0 0 90)
			(layer "B.SilkS")
			(hide yes)
			(effects
				(font
					(size 1.27 1.27)
				)
				(justify mirror)
			)
		)
		(property "Value" ""
			(at 0 0 90)
			(layer "B.Fab")
			(effects
				(font
					(size 1.27 1.27)
				)
				(justify mirror)
			)
		)
		(duplicate_pad_numbers_are_jumpers no)
		(fp_line
			(start -0.7874 0.4064)
			(end 0.7874 0.4064)
			(stroke
				(width 0.1524)
				(type default)
			)
			(layer "B.SilkS")
		)
		(fp_line
			(start 0.7874 0.4064)
			(end 0.7874 -0.4064)
			(stroke
				(width 0.1524)
				(type default)
			)
			(layer "B.SilkS")
		)
		(fp_line
			(start -0.7874 -0.4064)
			(end -0.7874 0.4064)
			(stroke
				(width 0.1524)
				(type default)
			)
			(layer "B.SilkS")
		)
		(fp_line
			(start 0.7874 -0.4064)
			(end -0.7874 -0.4064)
			(stroke
				(width 0.1524)
				(type default)
			)
			(layer "B.SilkS")
		)
		(fp_line
			(start -0.67945 0.3048)
			(end -0.120396 0.3048)
			(stroke
				(width 0.1)
				(type default)
			)
			(layer "B.Fab")
		)
		(fp_line
			(start -0.120396 0.3048)
			(end -0.120396 0.2794)
			(stroke
				(width 0.1)
				(type default)
			)
			(layer "B.Fab")
		)
		(fp_line
			(start 0.12065 0.3048)
			(end 0.67945 0.3048)
			(stroke
				(width 0.1)
				(type default)
			)
			(layer "B.Fab")
		)
		(fp_line
			(start 0.67945 0.3048)
			(end 0.67945 -0.305054)
			(stroke
				(width 0.1)
				(type default)
			)
			(layer "B.Fab")
		)
		(fp_line
			(start -0.120396 0.2794)
			(end 0.12065 0.2794)
			(stroke
				(width 0.1)
				(type default)
			)
			(layer "B.Fab")
		)
		(fp_line
			(start 0.12065 0.2794)
			(end 0.12065 0.3048)
			(stroke
				(width 0.1)
				(type default)
			)
			(layer "B.Fab")
		)
		(fp_line
			(start -0.12065 -0.2794)
			(end -0.12065 -0.3048)
			(stroke
				(width 0.1)
				(type default)
			)
			(layer "B.Fab")
		)
		(fp_line
			(start 0.12065 -0.2794)
			(end -0.12065 -0.2794)
			(stroke
				(width 0.1)
				(type default)
			)
			(layer "B.Fab")
		)
		(fp_line
			(start -0.67945 -0.3048)
			(end -0.67945 0.3048)
			(stroke
				(width 0.1)
				(type default)
			)
			(layer "B.Fab")
		)
		(fp_line
			(start -0.12065 -0.3048)
			(end -0.67945 -0.3048)
			(stroke
				(width 0.1)
				(type default)
			)
			(layer "B.Fab")
		)
		(fp_line
			(start 0.12065 -0.305054)
			(end 0.12065 -0.2794)
			(stroke
				(width 0.1)
				(type default)
			)
			(layer "B.Fab")
		)
		(fp_line
			(start 0.67945 -0.305054)
			(end 0.12065 -0.305054)
			(stroke
				(width 0.1)
				(type default)
			)
			(layer "B.Fab")
		)
		(pad "1" smd rect
			(at 0.40005 0 270)
			(size 0.4572 0.508)
			(layers "B.Cu" "B.Mask" "B.Paste")
			(net "P12V_E1S_0_ISENSE_MPS_MAM")
		)
		(pad "2" smd rect
			(at -0.40005 0 270)
			(size 0.4572 0.508)
			(layers "B.Cu" "B.Mask" "B.Paste")
			(net "P12V_E1S_0_ISENSE_MAM")
		)
	)
	(footprint ""
		(layer "B.Cu")
		(at 206.248 -192.660016)
		(property "Reference" "C548"
			(at 0 0 0)
			(layer "B.SilkS")
			(hide yes)
			(effects
				(font
					(size 1.27 1.27)
				)
				(justify mirror)
			)
		)
		(property "Value" ""
			(at 0 0 0)
			(layer "B.Fab")
			(effects
				(font
					(size 1.27 1.27)
				)
				(justify mirror)
			)
		)
		(duplicate_pad_numbers_are_jumpers no)
		(fp_line
			(start -1.524 -0.762)
			(end -1.524 0.762)
			(stroke
				(width 0.1524)
				(type default)
			)
			(layer "B.SilkS")
		)
		(fp_line
			(start -1.524 0.762)
			(end 1.524 0.762)
			(stroke
				(width 0.1524)
				(type default)
			)
			(layer "B.SilkS")
		)
		(fp_line
			(start 1.524 -0.762)
			(end -1.524 -0.762)
			(stroke
				(width 0.1524)
				(type default)
			)
			(layer "B.SilkS")
		)
		(fp_line
			(start 1.524 0.762)
			(end 1.524 -0.762)
			(stroke
				(width 0.1524)
				(type default)
			)
			(layer "B.SilkS")
		)
		(fp_line
			(start -1.1049 -0.724916)
			(end 1.1049 -0.724916)
			(stroke
				(width 0.1)
				(type default)
			)
			(layer "B.Fab")
		)
		(fp_line
			(start -1.1049 0.724916)
			(end -1.1049 -0.724916)
			(stroke
				(width 0.1)
				(type default)
			)
			(layer "B.Fab")
		)
		(fp_line
			(start 1.1049 -0.724916)
			(end 1.1049 0.724916)
			(stroke
				(width 0.1)
				(type default)
			)
			(layer "B.Fab")
		)
		(fp_line
			(start 1.1049 0.724916)
			(end -1.1049 0.724916)
			(stroke
				(width 0.1)
				(type default)
			)
			(layer "B.Fab")
		)
		(pad "1" smd rect
			(at 0.889 0)
			(size 1.016 1.27)
			(layers "B.Cu" "B.Mask" "B.Paste")
			(net "P12V_MEM_CPU1")
		)
		(pad "2" smd rect
			(at -0.889 0)
			(size 1.016 1.27)
			(layers "B.Cu" "B.Mask" "B.Paste")
			(net "GND")
		)
	)
	(footprint ""
		(layer "B.Cu")
		(at 121.010172 -72.566022)
		(property "Reference" "R6240"
			(at 0 0 0)
			(layer "B.SilkS")
			(hide yes)
			(effects
				(font
					(size 1.27 1.27)
				)
				(justify mirror)
			)
		)
		(property "Value" ""
			(at 0 0 0)
			(layer "B.Fab")
			(effects
				(font
					(size 1.27 1.27)
				)
				(justify mirror)
			)
		)
		(duplicate_pad_numbers_are_jumpers no)
		(fp_line
			(start -0.7874 -0.4064)
			(end -0.7874 0.4064)
			(stroke
				(width 0.1524)
				(type default)
			)
			(layer "B.SilkS")
		)
		(fp_line
			(start -0.7874 0.4064)
			(end 0.7874 0.4064)
			(stroke
				(width 0.1524)
				(type default)
			)
			(layer "B.SilkS")
		)
		(fp_line
			(start 0.7874 -0.4064)
			(end -0.7874 -0.4064)
			(stroke
				(width 0.1524)
				(type default)
			)
			(layer "B.SilkS")
		)
		(fp_line
			(start 0.7874 0.4064)
			(end 0.7874 -0.4064)
			(stroke
				(width 0.1524)
				(type default)
			)
			(layer "B.SilkS")
		)
		(fp_line
			(start -0.67945 -0.3048)
			(end -0.67945 0.3048)
			(stroke
				(width 0.1)
				(type default)
			)
			(layer "B.Fab")
		)
		(fp_line
			(start -0.67945 0.3048)
			(end -0.120396 0.3048)
			(stroke
				(width 0.1)
				(type default)
			)
			(layer "B.Fab")
		)
		(fp_line
			(start -0.12065 -0.3048)
			(end -0.67945 -0.3048)
			(stroke
				(width 0.1)
				(type default)
			)
			(layer "B.Fab")
		)
		(fp_line
			(start -0.12065 -0.2794)
			(end -0.12065 -0.3048)
			(stroke
				(width 0.1)
				(type default)
			)
			(layer "B.Fab")
		)
		(fp_line
			(start -0.120396 0.2794)
			(end 0.12065 0.2794)
			(stroke
				(width 0.1)
				(type default)
			)
			(layer "B.Fab")
		)
		(fp_line
			(start -0.120396 0.3048)
			(end -0.120396 0.2794)
			(stroke
				(width 0.1)
				(type default)
			)
			(layer "B.Fab")
		)
		(fp_line
			(start 0.12065 -0.305054)
			(end 0.12065 -0.2794)
			(stroke
				(width 0.1)
				(type default)
			)
			(layer "B.Fab")
		)
		(fp_line
			(start 0.12065 -0.2794)
			(end -0.12065 -0.2794)
			(stroke
				(width 0.1)
				(type default)
			)
			(layer "B.Fab")
		)
		(fp_line
			(start 0.12065 0.2794)
			(end 0.12065 0.3048)
			(stroke
				(width 0.1)
				(type default)
			)
			(layer "B.Fab")
		)
		(fp_line
			(start 0.12065 0.3048)
			(end 0.67945 0.3048)
			(stroke
				(width 0.1)
				(type default)
			)
			(layer "B.Fab")
		)
		(fp_line
			(start 0.67945 -0.305054)
			(end 0.12065 -0.305054)
			(stroke
				(width 0.1)
				(type default)
			)
			(layer "B.Fab")
		)
		(fp_line
			(start 0.67945 0.3048)
			(end 0.67945 -0.305054)
			(stroke
				(width 0.1)
				(type default)
			)
			(layer "B.Fab")
		)
		(pad "1" smd circle
			(at 0.40005 0 180)
			(size 0 0)
			(layers "B.Cu" "B.Mask" "B.Paste")
			(net "PWRGD_P1V8_AUX_R")
		)
		(pad "2" smd circle
			(at -0.40005 0 180)
			(size 0 0)
			(layers "B.Cu" "B.Mask" "B.Paste")
			(net "P1V2_AUX_ENABLE")
		)
	)
	(footprint ""
		(layer "B.Cu")
		(at 177.278284 -421.217598)
		(property "Reference" "R6210"
			(at 0 0 0)
			(layer "B.SilkS")
			(hide yes)
			(effects
				(font
					(size 1.27 1.27)
				)
				(justify mirror)
			)
		)
		(property "Value" ""
			(at 0 0 0)
			(layer "B.Fab")
			(effects
				(font
					(size 1.27 1.27)
				)
				(justify mirror)
			)
		)
		(duplicate_pad_numbers_are_jumpers no)
		(fp_line
			(start -0.7874 -0.4064)
			(end -0.7874 0.4064)
			(stroke
				(width 0.1524)
				(type default)
			)
			(layer "B.SilkS")
		)
		(fp_line
			(start -0.7874 0.4064)
			(end 0.7874 0.4064)
			(stroke
				(width 0.1524)
				(type default)
			)
			(layer "B.SilkS")
		)
		(fp_line
			(start 0.7874 -0.4064)
			(end -0.7874 -0.4064)
			(stroke
				(width 0.1524)
				(type default)
			)
			(layer "B.SilkS")
		)
		(fp_line
			(start 0.7874 0.4064)
			(end 0.7874 -0.4064)
			(stroke
				(width 0.1524)
				(type default)
			)
			(layer "B.SilkS")
		)
		(fp_line
			(start -0.67945 -0.3048)
			(end -0.67945 0.3048)
			(stroke
				(width 0.1)
				(type default)
			)
			(layer "B.Fab")
		)
		(fp_line
			(start -0.67945 0.3048)
			(end -0.120396 0.3048)
			(stroke
				(width 0.1)
				(type default)
			)
			(layer "B.Fab")
		)
		(fp_line
			(start -0.12065 -0.3048)
			(end -0.67945 -0.3048)
			(stroke
				(width 0.1)
				(type default)
			)
			(layer "B.Fab")
		)
		(fp_line
			(start -0.12065 -0.2794)
			(end -0.12065 -0.3048)
			(stroke
				(width 0.1)
				(type default)
			)
			(layer "B.Fab")
		)
		(fp_line
			(start -0.120396 0.2794)
			(end 0.12065 0.2794)
			(stroke
				(width 0.1)
				(type default)
			)
			(layer "B.Fab")
		)
		(fp_line
			(start -0.120396 0.3048)
			(end -0.120396 0.2794)
			(stroke
				(width 0.1)
				(type default)
			)
			(layer "B.Fab")
		)
		(fp_line
			(start 0.12065 -0.305054)
			(end 0.12065 -0.2794)
			(stroke
				(width 0.1)
				(type default)
			)
			(layer "B.Fab")
		)
		(fp_line
			(start 0.12065 -0.2794)
			(end -0.12065 -0.2794)
			(stroke
				(width 0.1)
				(type default)
			)
			(layer "B.Fab")
		)
		(fp_line
			(start 0.12065 0.2794)
			(end 0.12065 0.3048)
			(stroke
				(width 0.1)
				(type default)
			)
			(layer "B.Fab")
		)
		(fp_line
			(start 0.12065 0.3048)
			(end 0.67945 0.3048)
			(stroke
				(width 0.1)
				(type default)
			)
			(layer "B.Fab")
		)
		(fp_line
			(start 0.67945 -0.305054)
			(end 0.12065 -0.305054)
			(stroke
				(width 0.1)
				(type default)
			)
			(layer "B.Fab")
		)
		(fp_line
			(start 0.67945 0.3048)
			(end 0.67945 -0.305054)
			(stroke
				(width 0.1)
				(type default)
			)
			(layer "B.Fab")
		)
		(pad "1" smd circle
			(at 0.40005 0 180)
			(size 0 0)
			(layers "B.Cu" "B.Mask" "B.Paste")
			(net "HSC_CSOUT")
		)
		(pad "2" smd circle
			(at -0.40005 0 180)
			(size 0 0)
			(layers "B.Cu" "B.Mask" "B.Paste")
			(net "HSC_D_OC")
		)
	)
)
